(kicad_pcb
	(version 20260206)
	(generator "pcbnew")
	(generator_version "10.0")
	(general
		(thickness 1.6)
		(legacy_teardrops no)
	)
	(paper "A4")
	(title_block
		(title "04192023_DAF0TMB3IC0_F0TG_MB_C_brd_V02_OCP.brd")
		(comment 1 "Grand Teton / footprints 1743-1748 of 8354")
	)
	(layers
		(0 "F.Cu" signal "TOP")
		(4 "In1.Cu" signal "GND")
		(6 "In2.Cu" signal "IN1")
		(8 "In3.Cu" signal "GND1")
		(10 "In4.Cu" signal "IN2")
		(12 "In5.Cu" signal "GND2")
		(14 "In6.Cu" signal "IN3")
		(16 "In7.Cu" signal "GND3")
		(18 "In8.Cu" signal "VCC")
		(20 "In9.Cu" signal "VCC1")
		(22 "In10.Cu" signal "GND4")
		(24 "In11.Cu" signal "IN4")
		(26 "In12.Cu" signal "GND5")
		(28 "In13.Cu" signal "IN5")
		(30 "In14.Cu" signal "GND6")
		(32 "In15.Cu" signal "IN6")
		(34 "In16.Cu" signal "GND7")
		(2 "B.Cu" signal "BOTTOM")
		(9 "F.Adhes" user "F.Adhesive")
		(11 "B.Adhes" user "B.Adhesive")
		(13 "F.Paste" user "Package Geometry/Pastemask Top")
		(15 "B.Paste" user "Package Geometry/Pastemask Bottom")
		(5 "F.SilkS" user "Ref Des/Silkscreen Top")
		(7 "B.SilkS" user "Ref Des/Silkscreen Bottom")
		(1 "F.Mask" user "Board Geometry/Soldermask Top")
		(3 "B.Mask" user "Board Geometry/Soldermask Bottom")
		(17 "Dwgs.User" user "User.Drawings")
		(19 "Cmts.User" user "User.Comments")
		(21 "Eco1.User" user "User.Eco1")
		(23 "Eco2.User" user "User.Eco2")
		(25 "Edge.Cuts" user "Board Geometry/Outline")
		(27 "Margin" user)
		(31 "F.CrtYd" user "Package Geometry/Place Bound Top")
		(29 "B.CrtYd" user "Package Geometry/Place Bound Bottom")
		(35 "F.Fab" user "Ref Des/Assembly Top")
		(33 "B.Fab" user "Ref Des/Assembly Bottom")
	)
	(footprint ""
		(layer "F.Cu")
		(at 439.072782 -437.34736 -90)
		(property "Reference" "C5"
			(at 0 0 270)
			(layer "F.SilkS")
			(hide yes)
			(effects
				(font
					(size 1.27 1.27)
				)
			)
		)
		(property "Value" ""
			(at 0 0 270)
			(layer "F.Fab")
			(effects
				(font
					(size 1.27 1.27)
				)
			)
		)
		(duplicate_pad_numbers_are_jumpers no)
		(fp_line
			(start -0.7874 0.4064)
			(end -0.7874 -0.4064)
			(stroke
				(width 0.1524)
				(type default)
			)
			(layer "F.SilkS")
		)
		(fp_line
			(start 0.7874 0.4064)
			(end -0.7874 0.4064)
			(stroke
				(width 0.1524)
				(type default)
			)
			(layer "F.SilkS")
		)
		(fp_line
			(start -0.7874 -0.4064)
			(end 0.7874 -0.4064)
			(stroke
				(width 0.1524)
				(type default)
			)
			(layer "F.SilkS")
		)
		(fp_line
			(start 0.7874 -0.4064)
			(end 0.7874 0.4064)
			(stroke
				(width 0.1524)
				(type default)
			)
			(layer "F.SilkS")
		)
		(fp_line
			(start -0.67945 0.3048)
			(end -0.67945 -0.305054)
			(stroke
				(width 0.1)
				(type default)
			)
			(layer "F.Fab")
		)
		(fp_line
			(start -0.12065 0.3048)
			(end -0.67945 0.3048)
			(stroke
				(width 0.1)
				(type default)
			)
			(layer "F.Fab")
		)
		(fp_line
			(start 0.120396 0.3048)
			(end 0.120396 0.2794)
			(stroke
				(width 0.1)
				(type default)
			)
			(layer "F.Fab")
		)
		(fp_line
			(start 0.67945 0.3048)
			(end 0.120396 0.3048)
			(stroke
				(width 0.1)
				(type default)
			)
			(layer "F.Fab")
		)
		(fp_line
			(start -0.12065 0.2794)
			(end -0.12065 0.3048)
			(stroke
				(width 0.1)
				(type default)
			)
			(layer "F.Fab")
		)
		(fp_line
			(start 0.120396 0.2794)
			(end -0.12065 0.2794)
			(stroke
				(width 0.1)
				(type default)
			)
			(layer "F.Fab")
		)
		(fp_line
			(start -0.12065 -0.2794)
			(end 0.12065 -0.2794)
			(stroke
				(width 0.1)
				(type default)
			)
			(layer "F.Fab")
		)
		(fp_line
			(start 0.12065 -0.2794)
			(end 0.12065 -0.3048)
			(stroke
				(width 0.1)
				(type default)
			)
			(layer "F.Fab")
		)
		(fp_line
			(start 0.12065 -0.3048)
			(end 0.67945 -0.3048)
			(stroke
				(width 0.1)
				(type default)
			)
			(layer "F.Fab")
		)
		(fp_line
			(start 0.67945 -0.3048)
			(end 0.67945 0.3048)
			(stroke
				(width 0.1)
				(type default)
			)
			(layer "F.Fab")
		)
		(fp_line
			(start -0.67945 -0.305054)
			(end -0.12065 -0.305054)
			(stroke
				(width 0.1)
				(type default)
			)
			(layer "F.Fab")
		)
		(fp_line
			(start -0.12065 -0.305054)
			(end -0.12065 -0.2794)
			(stroke
				(width 0.1)
				(type default)
			)
			(layer "F.Fab")
		)
		(pad "1" smd circle
			(at -0.40005 0 270)
			(size 0 0)
			(layers "F.Cu" "F.Mask" "F.Paste")
			(net "GPU_3V3IO_RSVD4_ISO")
		)
		(pad "2" smd circle
			(at 0.40005 0 270)
			(size 0 0)
			(layers "F.Cu" "F.Mask" "F.Paste")
			(net "GND")
		)
	)
	(footprint ""
		(layer "F.Cu")
		(at 431.970688 -342.307164 -90)
		(property "Reference" "PL22"
			(at -2.116836 -4.808982 90)
			(unlocked yes)
			(layer "F.SilkS")
			(effects
				(font
					(size 0.7874 0.5842)
					(thickness 0.1524)
				)
				(justify left)
			)
		)
		(property "Value" ""
			(at 0 0 270)
			(layer "F.Fab")
			(effects
				(font
					(size 1.27 1.27)
				)
			)
		)
		(duplicate_pad_numbers_are_jumpers no)
		(fp_line
			(start -4.99999 3.849878)
			(end -4.99999 2.23901)
			(stroke
				(width 0.1524)
				(type default)
			)
			(layer "F.SilkS")
		)
		(fp_line
			(start 4.99999 3.849878)
			(end -4.99999 3.849878)
			(stroke
				(width 0.1524)
				(type default)
			)
			(layer "F.SilkS")
		)
		(fp_line
			(start 4.99999 2.23901)
			(end 4.99999 3.849878)
			(stroke
				(width 0.1524)
				(type default)
			)
			(layer "F.SilkS")
		)
		(fp_line
			(start -4.99999 -2.23901)
			(end -4.99999 -3.849878)
			(stroke
				(width 0.1524)
				(type default)
			)
			(layer "F.SilkS")
		)
		(fp_line
			(start -4.99999 -3.849878)
			(end 4.99999 -3.849878)
			(stroke
				(width 0.1524)
				(type default)
			)
			(layer "F.SilkS")
		)
		(fp_line
			(start 4.99999 -3.849878)
			(end 4.99999 -2.23901)
			(stroke
				(width 0.1524)
				(type default)
			)
			(layer "F.SilkS")
		)
		(fp_line
			(start -4.99999 3.849878)
			(end -4.99999 -3.849878)
			(stroke
				(width 0.1)
				(type default)
			)
			(layer "F.Fab")
		)
		(fp_line
			(start 4.99999 3.849878)
			(end -4.99999 3.849878)
			(stroke
				(width 0.1)
				(type default)
			)
			(layer "F.Fab")
		)
		(fp_line
			(start -4.99999 -3.849878)
			(end 4.99999 -3.849878)
			(stroke
				(width 0.1)
				(type default)
			)
			(layer "F.Fab")
		)
		(fp_line
			(start 4.99999 -3.849878)
			(end 4.99999 3.849878)
			(stroke
				(width 0.1)
				(type default)
			)
			(layer "F.Fab")
		)
		(pad "1" smd rect
			(at -3.299968 0 270)
			(size 3.302 4.2164)
			(layers "F.Cu" "F.Mask" "F.Paste")
			(net "SW_PVDD11_S3_P0_SW2")
		)
		(pad "2" smd rect
			(at 3.299968 0 270)
			(size 3.302 4.2164)
			(layers "F.Cu" "F.Mask" "F.Paste")
			(net "PVDD11_S3_P0")
		)
	)
	(footprint ""
		(layer "F.Cu")
		(at 226.0981 -406.052782)
		(property "Reference" "PR3993"
			(at 0 0 0)
			(layer "F.SilkS")
			(hide yes)
			(effects
				(font
					(size 1.27 1.27)
				)
			)
		)
		(property "Value" ""
			(at 0 0 0)
			(layer "F.Fab")
			(effects
				(font
					(size 1.27 1.27)
				)
			)
		)
		(duplicate_pad_numbers_are_jumpers no)
		(fp_line
			(start -0.7874 -0.4064)
			(end 0.7874 -0.4064)
			(stroke
				(width 0.1524)
				(type default)
			)
			(layer "F.SilkS")
		)
		(fp_line
			(start -0.7874 0.4064)
			(end -0.7874 -0.4064)
			(stroke
				(width 0.1524)
				(type default)
			)
			(layer "F.SilkS")
		)
		(fp_line
			(start 0.7874 -0.4064)
			(end 0.7874 0.4064)
			(stroke
				(width 0.1524)
				(type default)
			)
			(layer "F.SilkS")
		)
		(fp_line
			(start 0.7874 0.4064)
			(end -0.7874 0.4064)
			(stroke
				(width 0.1524)
				(type default)
			)
			(layer "F.SilkS")
		)
		(fp_line
			(start -0.67945 -0.305054)
			(end -0.12065 -0.305054)
			(stroke
				(width 0.1)
				(type default)
			)
			(layer "F.Fab")
		)
		(fp_line
			(start -0.67945 0.3048)
			(end -0.67945 -0.305054)
			(stroke
				(width 0.1)
				(type default)
			)
			(layer "F.Fab")
		)
		(fp_line
			(start -0.12065 -0.305054)
			(end -0.12065 -0.2794)
			(stroke
				(width 0.1)
				(type default)
			)
			(layer "F.Fab")
		)
		(fp_line
			(start -0.12065 -0.2794)
			(end 0.12065 -0.2794)
			(stroke
				(width 0.1)
				(type default)
			)
			(layer "F.Fab")
		)
		(fp_line
			(start -0.12065 0.2794)
			(end -0.12065 0.3048)
			(stroke
				(width 0.1)
				(type default)
			)
			(layer "F.Fab")
		)
		(fp_line
			(start -0.12065 0.3048)
			(end -0.67945 0.3048)
			(stroke
				(width 0.1)
				(type default)
			)
			(layer "F.Fab")
		)
		(fp_line
			(start 0.120396 0.2794)
			(end -0.12065 0.2794)
			(stroke
				(width 0.1)
				(type default)
			)
			(layer "F.Fab")
		)
		(fp_line
			(start 0.120396 0.3048)
			(end 0.120396 0.2794)
			(stroke
				(width 0.1)
				(type default)
			)
			(layer "F.Fab")
		)
		(fp_line
			(start 0.12065 -0.3048)
			(end 0.67945 -0.3048)
			(stroke
				(width 0.1)
				(type default)
			)
			(layer "F.Fab")
		)
		(fp_line
			(start 0.12065 -0.2794)
			(end 0.12065 -0.3048)
			(stroke
				(width 0.1)
				(type default)
			)
			(layer "F.Fab")
		)
		(fp_line
			(start 0.67945 -0.3048)
			(end 0.67945 0.3048)
			(stroke
				(width 0.1)
				(type default)
			)
			(layer "F.Fab")
		)
		(fp_line
			(start 0.67945 0.3048)
			(end 0.120396 0.3048)
			(stroke
				(width 0.1)
				(type default)
			)
			(layer "F.Fab")
		)
		(pad "1" smd circle
			(at -0.40005 0)
			(size 0 0)
			(layers "F.Cu" "F.Mask" "F.Paste")
			(net "HSC_FLT_TYPE_3")
		)
		(pad "2" smd circle
			(at 0.40005 0)
			(size 0 0)
			(layers "F.Cu" "F.Mask" "F.Paste")
			(net "HSC_FLT_TYPE")
		)
	)
	(footprint ""
		(layer "F.Cu")
		(at 253.506224 -131.067556 180)
		(property "Reference" "R603"
			(at 0 0 180)
			(layer "F.SilkS")
			(hide yes)
			(effects
				(font
					(size 1.27 1.27)
				)
			)
		)
		(property "Value" ""
			(at 0 0 180)
			(layer "F.Fab")
			(effects
				(font
					(size 1.27 1.27)
				)
			)
		)
		(duplicate_pad_numbers_are_jumpers no)
		(fp_line
			(start 0.7874 0.4064)
			(end -0.7874 0.4064)
			(stroke
				(width 0.1524)
				(type default)
			)
			(layer "F.SilkS")
		)
		(fp_line
			(start 0.7874 -0.4064)
			(end 0.7874 0.4064)
			(stroke
				(width 0.1524)
				(type default)
			)
			(layer "F.SilkS")
		)
		(fp_line
			(start -0.7874 0.4064)
			(end -0.7874 -0.4064)
			(stroke
				(width 0.1524)
				(type default)
			)
			(layer "F.SilkS")
		)
		(fp_line
			(start -0.7874 -0.4064)
			(end 0.7874 -0.4064)
			(stroke
				(width 0.1524)
				(type default)
			)
			(layer "F.SilkS")
		)
		(fp_line
			(start 0.67945 0.3048)
			(end 0.120396 0.3048)
			(stroke
				(width 0.1)
				(type default)
			)
			(layer "F.Fab")
		)
		(fp_line
			(start 0.67945 -0.3048)
			(end 0.67945 0.3048)
			(stroke
				(width 0.1)
				(type default)
			)
			(layer "F.Fab")
		)
		(fp_line
			(start 0.12065 -0.2794)
			(end 0.12065 -0.3048)
			(stroke
				(width 0.1)
				(type default)
			)
			(layer "F.Fab")
		)
		(fp_line
			(start 0.12065 -0.3048)
			(end 0.67945 -0.3048)
			(stroke
				(width 0.1)
				(type default)
			)
			(layer "F.Fab")
		)
		(fp_line
			(start 0.120396 0.3048)
			(end 0.120396 0.2794)
			(stroke
				(width 0.1)
				(type default)
			)
			(layer "F.Fab")
		)
		(fp_line
			(start 0.120396 0.2794)
			(end -0.12065 0.2794)
			(stroke
				(width 0.1)
				(type default)
			)
			(layer "F.Fab")
		)
		(fp_line
			(start -0.12065 0.3048)
			(end -0.67945 0.3048)
			(stroke
				(width 0.1)
				(type default)
			)
			(layer "F.Fab")
		)
		(fp_line
			(start -0.12065 0.2794)
			(end -0.12065 0.3048)
			(stroke
				(width 0.1)
				(type default)
			)
			(layer "F.Fab")
		)
		(fp_line
			(start -0.12065 -0.2794)
			(end 0.12065 -0.2794)
			(stroke
				(width 0.1)
				(type default)
			)
			(layer "F.Fab")
		)
		(fp_line
			(start -0.12065 -0.305054)
			(end -0.12065 -0.2794)
			(stroke
				(width 0.1)
				(type default)
			)
			(layer "F.Fab")
		)
		(fp_line
			(start -0.67945 0.3048)
			(end -0.67945 -0.305054)
			(stroke
				(width 0.1)
				(type default)
			)
			(layer "F.Fab")
		)
		(fp_line
			(start -0.67945 -0.305054)
			(end -0.12065 -0.305054)
			(stroke
				(width 0.1)
				(type default)
			)
			(layer "F.Fab")
		)
		(pad "1" smd circle
			(at -0.40005 0 180)
			(size 0 0)
			(layers "F.Cu" "F.Mask" "F.Paste")
			(net "SPI_CPU0_LVC3_CS0_N")
		)
		(pad "2" smd circle
			(at 0.40005 0 180)
			(size 0 0)
			(layers "F.Cu" "F.Mask" "F.Paste")
			(net "SPI_CPU0_LVC3_SCM_CS0_N")
		)
	)
	(footprint ""
		(layer "F.Cu")
		(at 171.26966 -387.763004 180)
		(property "Reference" "R857"
			(at 0 0 180)
			(layer "F.SilkS")
			(hide yes)
			(effects
				(font
					(size 1.27 1.27)
				)
			)
		)
		(property "Value" ""
			(at 0 0 180)
			(layer "F.Fab")
			(effects
				(font
					(size 1.27 1.27)
				)
			)
		)
		(duplicate_pad_numbers_are_jumpers no)
		(fp_line
			(start 0.7874 0.4064)
			(end -0.7874 0.4064)
			(stroke
				(width 0.1524)
				(type default)
			)
			(layer "F.SilkS")
		)
		(fp_line
			(start 0.7874 -0.4064)
			(end 0.7874 0.4064)
			(stroke
				(width 0.1524)
				(type default)
			)
			(layer "F.SilkS")
		)
		(fp_line
			(start -0.7874 0.4064)
			(end -0.7874 -0.4064)
			(stroke
				(width 0.1524)
				(type default)
			)
			(layer "F.SilkS")
		)
		(fp_line
			(start -0.7874 -0.4064)
			(end 0.7874 -0.4064)
			(stroke
				(width 0.1524)
				(type default)
			)
			(layer "F.SilkS")
		)
		(fp_line
			(start 0.67945 0.3048)
			(end 0.120396 0.3048)
			(stroke
				(width 0.1)
				(type default)
			)
			(layer "F.Fab")
		)
		(fp_line
			(start 0.67945 -0.3048)
			(end 0.67945 0.3048)
			(stroke
				(width 0.1)
				(type default)
			)
			(layer "F.Fab")
		)
		(fp_line
			(start 0.12065 -0.2794)
			(end 0.12065 -0.3048)
			(stroke
				(width 0.1)
				(type default)
			)
			(layer "F.Fab")
		)
		(fp_line
			(start 0.12065 -0.3048)
			(end 0.67945 -0.3048)
			(stroke
				(width 0.1)
				(type default)
			)
			(layer "F.Fab")
		)
		(fp_line
			(start 0.120396 0.3048)
			(end 0.120396 0.2794)
			(stroke
				(width 0.1)
				(type default)
			)
			(layer "F.Fab")
		)
		(fp_line
			(start 0.120396 0.2794)
			(end -0.12065 0.2794)
			(stroke
				(width 0.1)
				(type default)
			)
			(layer "F.Fab")
		)
		(fp_line
			(start -0.12065 0.3048)
			(end -0.67945 0.3048)
			(stroke
				(width 0.1)
				(type default)
			)
			(layer "F.Fab")
		)
		(fp_line
			(start -0.12065 0.2794)
			(end -0.12065 0.3048)
			(stroke
				(width 0.1)
				(type default)
			)
			(layer "F.Fab")
		)
		(fp_line
			(start -0.12065 -0.2794)
			(end 0.12065 -0.2794)
			(stroke
				(width 0.1)
				(type default)
			)
			(layer "F.Fab")
		)
		(fp_line
			(start -0.12065 -0.305054)
			(end -0.12065 -0.2794)
			(stroke
				(width 0.1)
				(type default)
			)
			(layer "F.Fab")
		)
		(fp_line
			(start -0.67945 0.3048)
			(end -0.67945 -0.305054)
			(stroke
				(width 0.1)
				(type default)
			)
			(layer "F.Fab")
		)
		(fp_line
			(start -0.67945 -0.305054)
			(end -0.12065 -0.305054)
			(stroke
				(width 0.1)
				(type default)
			)
			(layer "F.Fab")
		)
		(pad "1" smd rect
			(at -0.40005 0)
			(size 0.4572 0.508)
			(layers "F.Cu" "F.Mask" "F.Paste")
			(net "P1V8_CPU1_RT_1D")
		)
		(pad "2" smd rect
			(at 0.40005 0)
			(size 0.4572 0.508)
			(layers "F.Cu" "F.Mask" "F.Paste")
			(net "P1V8_CPU1_RT2_1A_1D")
		)
	)
	(footprint ""
		(layer "F.Cu")
		(at 376.811286 -178.359562 180)
		(property "Reference" "PC552_3"
			(at 0 0 180)
			(layer "F.SilkS")
			(hide yes)
			(effects
				(font
					(size 1.27 1.27)
				)
			)
		)
		(property "Value" ""
			(at 0 0 180)
			(layer "F.Fab")
			(effects
				(font
					(size 1.27 1.27)
				)
			)
		)
		(duplicate_pad_numbers_are_jumpers no)
		(fp_line
			(start 0.7874 0.4064)
			(end -0.7874 0.4064)
			(stroke
				(width 0.1524)
				(type default)
			)
			(layer "F.SilkS")
		)
		(fp_line
			(start 0.7874 -0.4064)
			(end 0.7874 0.4064)
			(stroke
				(width 0.1524)
				(type default)
			)
			(layer "F.SilkS")
		)
		(fp_line
			(start -0.7874 0.4064)
			(end -0.7874 -0.4064)
			(stroke
				(width 0.1524)
				(type default)
			)
			(layer "F.SilkS")
		)
		(fp_line
			(start -0.7874 -0.4064)
			(end 0.7874 -0.4064)
			(stroke
				(width 0.1524)
				(type default)
			)
			(layer "F.SilkS")
		)
		(fp_line
			(start 0.67945 0.3048)
			(end 0.120396 0.3048)
			(stroke
				(width 0.1)
				(type default)
			)
			(layer "F.Fab")
		)
		(fp_line
			(start 0.67945 -0.3048)
			(end 0.67945 0.3048)
			(stroke
				(width 0.1)
				(type default)
			)
			(layer "F.Fab")
		)
		(fp_line
			(start 0.12065 -0.2794)
			(end 0.12065 -0.3048)
			(stroke
				(width 0.1)
				(type default)
			)
			(layer "F.Fab")
		)
		(fp_line
			(start 0.12065 -0.3048)
			(end 0.67945 -0.3048)
			(stroke
				(width 0.1)
				(type default)
			)
			(layer "F.Fab")
		)
		(fp_line
			(start 0.120396 0.3048)
			(end 0.120396 0.2794)
			(stroke
				(width 0.1)
				(type default)
			)
			(layer "F.Fab")
		)
		(fp_line
			(start 0.120396 0.2794)
			(end -0.12065 0.2794)
			(stroke
				(width 0.1)
				(type default)
			)
			(layer "F.Fab")
		)
		(fp_line
			(start -0.12065 0.3048)
			(end -0.67945 0.3048)
			(stroke
				(width 0.1)
				(type default)
			)
			(layer "F.Fab")
		)
		(fp_line
			(start -0.12065 0.2794)
			(end -0.12065 0.3048)
			(stroke
				(width 0.1)
				(type default)
			)
			(layer "F.Fab")
		)
		(fp_line
			(start -0.12065 -0.2794)
			(end 0.12065 -0.2794)
			(stroke
				(width 0.1)
				(type default)
			)
			(layer "F.Fab")
		)
		(fp_line
			(start -0.12065 -0.305054)
			(end -0.12065 -0.2794)
			(stroke
				(width 0.1)
				(type default)
			)
			(layer "F.Fab")
		)
		(fp_line
			(start -0.67945 0.3048)
			(end -0.67945 -0.305054)
			(stroke
				(width 0.1)
				(type default)
			)
			(layer "F.Fab")
		)
		(fp_line
			(start -0.67945 -0.305054)
			(end -0.12065 -0.305054)
			(stroke
				(width 0.1)
				(type default)
			)
			(layer "F.Fab")
		)
		(pad "1" smd circle
			(at -0.40005 0 180)
			(size 0 0)
			(layers "F.Cu" "F.Mask" "F.Paste")
			(net "SW_P12V_AUX_PVDDCR_CPU0_P0_FLT")
		)
		(pad "2" smd circle
			(at 0.40005 0 180)
			(size 0 0)
			(layers "F.Cu" "F.Mask" "F.Paste")
			(net "GND")
		)
	)
)
